(kicad_pcb
	(version 20260206)
	(generator "pcbnew")
	(generator_version "10.0")
	(general
		(thickness 1.6)
		(legacy_teardrops no)
	)
	(paper "A4")
	(title_block
		(title "v1-chassis-manager — T6M_CM_d_v01_1031_1645.brd")
		(comment 1 "Open CloudServer (Microsoft) / footprint 1388 of 2512 (J18), pads 1-120 of 164")
	)
	(layers
		(0 "F.Cu" signal "TOP")
		(4 "In1.Cu" signal "GND1")
		(6 "In2.Cu" signal "IN1")
		(8 "In3.Cu" signal "VCC1")
		(10 "In4.Cu" signal "VCC2")
		(12 "In5.Cu" signal "GND2")
		(14 "In6.Cu" signal "IN2")
		(16 "In7.Cu" signal "IN3")
		(18 "In8.Cu" signal "GND3")
		(2 "B.Cu" signal "BOTTOM")
		(9 "F.Adhes" user "F.Adhesive")
		(11 "B.Adhes" user "B.Adhesive")
		(13 "F.Paste" user "Package Geometry/Pastemask Top")
		(15 "B.Paste" user "Package Geometry/Pastemask Bottom")
		(5 "F.SilkS" user "Ref Des/Silkscreen Top")
		(7 "B.SilkS" user "Ref Des/Silkscreen Bottom")
		(1 "F.Mask" user "Board Geometry/Soldermask Top")
		(3 "B.Mask" user "Board Geometry/Soldermask Bottom")
		(17 "Dwgs.User" user "User.Drawings")
		(19 "Cmts.User" user "User.Comments")
		(21 "Eco1.User" user "User.Eco1")
		(23 "Eco2.User" user "User.Eco2")
		(25 "Edge.Cuts" user "Board Geometry/Outline")
		(27 "Margin" user)
		(31 "F.CrtYd" user "Package Geometry/Place Bound Top")
		(29 "B.CrtYd" user "Package Geometry/Place Bound Bottom")
		(35 "F.Fab" user "Ref Des/Assembly Top")
		(33 "B.Fab" user "Ref Des/Assembly Bottom")
	)
	(footprint ""
		(layer "F.Cu")
		(at 145.515584 -205.199488 180)
		(property "Reference" "J18"
			(at 41.139364 -7.366762 0)
			(unlocked yes)
			(layer "F.SilkS")
			(effects
				(font
					(size 0.7874 0.5842)
					(thickness 0.1524)
				)
				(justify left)
			)
		)
		(property "Value" ""
			(at 0 0 180)
			(layer "F.Fab")
			(effects
				(font
					(size 1.27 1.27)
				)
			)
		)
		(duplicate_pad_numbers_are_jumpers no)
		(pad "A1" smd rect
			(at -41.500044 -0.499872 180)
			(size 0.762 3.2004)
			(layers "F.Cu" "F.Mask" "F.Paste")
			(net "GND")
		)
		(pad "A2" smd rect
			(at -40.500046 0 180)
			(size 0.762 4.2164)
			(layers "F.Cu" "F.Mask" "F.Paste")
			(net "GND")
		)
		(pad "A3" smd rect
			(at -39.500048 0 180)
			(size 0.762 4.2164)
			(layers "F.Cu" "F.Mask" "F.Paste")
			(net "LAN2_P3_P")
		)
		(pad "A4" smd rect
			(at -38.50005 0 180)
			(size 0.762 4.2164)
			(layers "F.Cu" "F.Mask" "F.Paste")
			(net "LAN2_P3_N")
		)
		(pad "A5" smd rect
			(at -37.500052 0 180)
			(size 0.762 4.2164)
			(layers "F.Cu" "F.Mask" "F.Paste")
			(net "GND")
		)
		(pad "A6" smd rect
			(at -36.500054 0 180)
			(size 0.762 4.2164)
			(layers "F.Cu" "F.Mask" "F.Paste")
			(net "LAN2_P4_P")
		)
		(pad "A7" smd rect
			(at -35.500056 0 180)
			(size 0.762 4.2164)
			(layers "F.Cu" "F.Mask" "F.Paste")
			(net "LAN2_P4_N")
		)
		(pad "A8" smd rect
			(at -34.500058 0 180)
			(size 0.762 4.2164)
			(layers "F.Cu" "F.Mask" "F.Paste")
			(net "GND")
		)
		(pad "A9" smd rect
			(at -33.50006 0 180)
			(size 0.762 4.2164)
			(layers "F.Cu" "F.Mask" "F.Paste")
			(net "POWER_SW3_PWR_CTR_12V_R")
		)
		(pad "A10" smd rect
			(at -32.500062 0 180)
			(size 0.762 4.2164)
			(layers "F.Cu" "F.Mask" "F.Paste")
			(net "POWER_SW2_PWR_CTR_12V_R")
		)
		(pad "A11" smd rect
			(at -31.500064 0 180)
			(size 0.762 4.2164)
			(layers "F.Cu" "F.Mask" "F.Paste")
			(net "POWER_SW1_PWR_CTR_12V_R")
		)
		(pad "A12" smd rect
			(at -28.50007 0 180)
			(size 0.762 4.2164)
			(layers "F.Cu" "F.Mask" "F.Paste")
			(net "GND2")
		)
		(pad "A13" smd rect
			(at -27.500072 0 180)
			(size 0.762 4.2164)
			(layers "F.Cu" "F.Mask" "F.Paste")
			(net "Net_225")
		)
		(pad "A14" smd rect
			(at -26.500074 0 180)
			(size 0.762 4.2164)
			(layers "F.Cu" "F.Mask" "F.Paste")
			(net "Net_226")
		)
		(pad "A15" smd rect
			(at -25.500076 0 180)
			(size 0.762 4.2164)
			(layers "F.Cu" "F.Mask" "F.Paste")
			(net "GND3")
		)
		(pad "A16" smd rect
			(at -24.500078 0 180)
			(size 0.762 4.2164)
			(layers "F.Cu" "F.Mask" "F.Paste")
			(net "Net_221")
		)
		(pad "A17" smd rect
			(at -23.50008 0 180)
			(size 0.762 4.2164)
			(layers "F.Cu" "F.Mask" "F.Paste")
			(net "GND")
		)
		(pad "A18" smd rect
			(at -22.500082 0 180)
			(size 0.762 4.2164)
			(layers "F.Cu" "F.Mask" "F.Paste")
			(net "UART_RTS_RP6_L_N")
		)
		(pad "A19" smd rect
			(at -21.500084 0 180)
			(size 0.762 4.2164)
			(layers "F.Cu" "F.Mask" "F.Paste")
			(net "UART_DSR_RP6_L_N")
		)
		(pad "A20" smd rect
			(at -20.500086 0 180)
			(size 0.762 4.2164)
			(layers "F.Cu" "F.Mask" "F.Paste")
			(net "UART_RX_RP6_L")
		)
		(pad "A21" smd rect
			(at -19.500088 0 180)
			(size 0.762 4.2164)
			(layers "F.Cu" "F.Mask" "F.Paste")
			(net "UART_TX_RP6_L")
		)
		(pad "A22" smd rect
			(at -18.50009 0 180)
			(size 0.762 4.2164)
			(layers "F.Cu" "F.Mask" "F.Paste")
			(net "UART_DTR_RP6_L_N")
		)
		(pad "A23" smd rect
			(at -17.500092 0 180)
			(size 0.762 4.2164)
			(layers "F.Cu" "F.Mask" "F.Paste")
			(net "UART_CTS_RP6_L")
		)
		(pad "A24" smd rect
			(at -16.500094 0 180)
			(size 0.762 4.2164)
			(layers "F.Cu" "F.Mask" "F.Paste")
			(net "UART_RI_RP6_L_N_R")
		)
		(pad "A25" smd rect
			(at -15.500096 0 180)
			(size 0.762 4.2164)
			(layers "F.Cu" "F.Mask" "F.Paste")
			(net "GND")
		)
		(pad "A26" smd rect
			(at -14.500098 0 180)
			(size 0.762 4.2164)
			(layers "F.Cu" "F.Mask" "F.Paste")
			(net "FAN4_TACH_R")
		)
		(pad "A27" smd rect
			(at -13.5001 0 180)
			(size 0.762 4.2164)
			(layers "F.Cu" "F.Mask" "F.Paste")
			(net "FAN5_TACH_R")
		)
		(pad "A28" smd rect
			(at -12.500102 0 180)
			(size 0.762 4.2164)
			(layers "F.Cu" "F.Mask" "F.Paste")
			(net "FAN6_TACH_R")
		)
		(pad "A29" smd rect
			(at -11.500104 0 180)
			(size 0.762 4.2164)
			(layers "F.Cu" "F.Mask" "F.Paste")
			(net "GND")
		)
		(pad "A30" smd rect
			(at -10.500106 0 180)
			(size 0.762 4.2164)
			(layers "F.Cu" "F.Mask" "F.Paste")
			(net "FAN_PWM_R")
		)
		(pad "A31" smd rect
			(at -9.500108 0 180)
			(size 0.762 4.2164)
			(layers "F.Cu" "F.Mask" "F.Paste")
			(net "GND")
		)
		(pad "A32" smd rect
			(at -8.50011 0 180)
			(size 0.762 4.2164)
			(layers "F.Cu" "F.Mask" "F.Paste")
			(net "I2C_PSU3_R_SCL")
		)
		(pad "A33" smd rect
			(at -7.500112 0 180)
			(size 0.762 4.2164)
			(layers "F.Cu" "F.Mask" "F.Paste")
			(net "I2C_PSU3_R_SDA")
		)
		(pad "A34" smd rect
			(at -6.500114 0 180)
			(size 0.762 4.2164)
			(layers "F.Cu" "F.Mask" "F.Paste")
			(net "GND")
		)
		(pad "A35" smd rect
			(at -5.500116 0 180)
			(size 0.762 4.2164)
			(layers "F.Cu" "F.Mask" "F.Paste")
			(net "T11_NODE1_EN_R")
		)
		(pad "A36" smd rect
			(at -4.500118 0 180)
			(size 0.762 4.2164)
			(layers "F.Cu" "F.Mask" "F.Paste")
			(net "T11_NODE2_EN_R")
		)
		(pad "A37" smd rect
			(at -3.50012 0 180)
			(size 0.762 4.2164)
			(layers "F.Cu" "F.Mask" "F.Paste")
			(net "T11_NODE3_EN_R")
		)
		(pad "A38" smd rect
			(at -2.500122 0 180)
			(size 0.762 4.2164)
			(layers "F.Cu" "F.Mask" "F.Paste")
			(net "T11_NODE4_EN_R")
		)
		(pad "A39" smd rect
			(at -1.500124 0 180)
			(size 0.762 4.2164)
			(layers "F.Cu" "F.Mask" "F.Paste")
			(net "GND")
		)
		(pad "A40" smd rect
			(at -0.499872 0 180)
			(size 0.762 4.2164)
			(layers "F.Cu" "F.Mask" "F.Paste")
			(net "UART_T11_NODE1_RXD_R")
		)
		(pad "A41" smd rect
			(at 0.499872 0 180)
			(size 0.762 4.2164)
			(layers "F.Cu" "F.Mask" "F.Paste")
			(net "UART_T11_NODE1_TXD_R")
		)
		(pad "A42" smd rect
			(at 1.500124 0 180)
			(size 0.762 4.2164)
			(layers "F.Cu" "F.Mask" "F.Paste")
			(net "UART_T11_NODE2_RXD_R")
		)
		(pad "A43" smd rect
			(at 2.500122 0 180)
			(size 0.762 4.2164)
			(layers "F.Cu" "F.Mask" "F.Paste")
			(net "UART_T11_NODE2_TXD_R")
		)
		(pad "A44" smd rect
			(at 3.50012 0 180)
			(size 0.762 4.2164)
			(layers "F.Cu" "F.Mask" "F.Paste")
			(net "GND")
		)
		(pad "A45" smd rect
			(at 4.500118 0 180)
			(size 0.762 4.2164)
			(layers "F.Cu" "F.Mask" "F.Paste")
			(net "UART_T11_NODE3_RXD_R")
		)
		(pad "A46" smd rect
			(at 5.500116 0 180)
			(size 0.762 4.2164)
			(layers "F.Cu" "F.Mask" "F.Paste")
			(net "UART_T11_NODE3_TXD_R")
		)
		(pad "A47" smd rect
			(at 6.500114 0 180)
			(size 0.762 4.2164)
			(layers "F.Cu" "F.Mask" "F.Paste")
			(net "UART_T11_NODE4_RXD_R")
		)
		(pad "A48" smd rect
			(at 7.500112 0 180)
			(size 0.762 4.2164)
			(layers "F.Cu" "F.Mask" "F.Paste")
			(net "UART_T11_NODE4_TXD_R")
		)
		(pad "A49" smd rect
			(at 8.50011 0 180)
			(size 0.762 4.2164)
			(layers "F.Cu" "F.Mask" "F.Paste")
			(net "GND")
		)
		(pad "A50" smd rect
			(at 9.500108 0 180)
			(size 0.762 4.2164)
			(layers "F.Cu" "F.Mask" "F.Paste")
			(net "T9_NODE1_EN_R")
		)
		(pad "A51" smd rect
			(at 10.500106 0 180)
			(size 0.762 4.2164)
			(layers "F.Cu" "F.Mask" "F.Paste")
			(net "T9_NODE2_EN_R")
		)
		(pad "A52" smd rect
			(at 11.500104 0 180)
			(size 0.762 4.2164)
			(layers "F.Cu" "F.Mask" "F.Paste")
			(net "T9_NODE3_EN_R")
		)
		(pad "A53" smd rect
			(at 12.500102 0 180)
			(size 0.762 4.2164)
			(layers "F.Cu" "F.Mask" "F.Paste")
			(net "T9_NODE4_EN_R")
		)
		(pad "A54" smd rect
			(at 13.5001 0 180)
			(size 0.762 4.2164)
			(layers "F.Cu" "F.Mask" "F.Paste")
			(net "GND")
		)
		(pad "A55" smd rect
			(at 14.500098 0 180)
			(size 0.762 4.2164)
			(layers "F.Cu" "F.Mask" "F.Paste")
			(net "UART_T9_NODE1_RXD_R")
		)
		(pad "A56" smd rect
			(at 15.500096 0 180)
			(size 0.762 4.2164)
			(layers "F.Cu" "F.Mask" "F.Paste")
			(net "UART_T9_NODE1_TXD_R")
		)
		(pad "A57" smd rect
			(at 16.500094 0 180)
			(size 0.762 4.2164)
			(layers "F.Cu" "F.Mask" "F.Paste")
			(net "UART_T9_NODE2_RXD_R")
		)
		(pad "A58" smd rect
			(at 17.500092 0 180)
			(size 0.762 4.2164)
			(layers "F.Cu" "F.Mask" "F.Paste")
			(net "UART_T9_NODE2_TXD_R")
		)
		(pad "A59" smd rect
			(at 18.50009 0 180)
			(size 0.762 4.2164)
			(layers "F.Cu" "F.Mask" "F.Paste")
			(net "GND")
		)
		(pad "A60" smd rect
			(at 19.500088 0 180)
			(size 0.762 4.2164)
			(layers "F.Cu" "F.Mask" "F.Paste")
			(net "UART_T9_NODE3_RXD_R")
		)
		(pad "A61" smd rect
			(at 20.500086 0 180)
			(size 0.762 4.2164)
			(layers "F.Cu" "F.Mask" "F.Paste")
			(net "UART_T9_NODE3_TXD_R")
		)
		(pad "A62" smd rect
			(at 21.500084 0 180)
			(size 0.762 4.2164)
			(layers "F.Cu" "F.Mask" "F.Paste")
			(net "UART_T9_NODE4_RXD_R")
		)
		(pad "A63" smd rect
			(at 22.500082 0 180)
			(size 0.762 4.2164)
			(layers "F.Cu" "F.Mask" "F.Paste")
			(net "UART_T9_NODE4_TXD_R")
		)
		(pad "A64" smd rect
			(at 23.50008 0 180)
			(size 0.762 4.2164)
			(layers "F.Cu" "F.Mask" "F.Paste")
			(net "GND")
		)
		(pad "A65" smd rect
			(at 24.500078 0 180)
			(size 0.762 4.2164)
			(layers "F.Cu" "F.Mask" "F.Paste")
			(net "T7_NODE1_EN_R")
		)
		(pad "A66" smd rect
			(at 25.500076 0 180)
			(size 0.762 4.2164)
			(layers "F.Cu" "F.Mask" "F.Paste")
			(net "T7_NODE2_EN_R")
		)
		(pad "A67" smd rect
			(at 26.500074 0 180)
			(size 0.762 4.2164)
			(layers "F.Cu" "F.Mask" "F.Paste")
			(net "T7_NODE3_EN_R")
		)
		(pad "A68" smd rect
			(at 27.500072 0 180)
			(size 0.762 4.2164)
			(layers "F.Cu" "F.Mask" "F.Paste")
			(net "T7_NODE4_EN_R")
		)
		(pad "A69" smd rect
			(at 28.50007 0 180)
			(size 0.762 4.2164)
			(layers "F.Cu" "F.Mask" "F.Paste")
			(net "GND")
		)
		(pad "A70" smd rect
			(at 29.500068 0 180)
			(size 0.762 4.2164)
			(layers "F.Cu" "F.Mask" "F.Paste")
			(net "UART_T7_NODE1_RXD_R")
		)
		(pad "A71" smd rect
			(at 30.500066 0 180)
			(size 0.762 4.2164)
			(layers "F.Cu" "F.Mask" "F.Paste")
			(net "UART_T7_NODE1_TXD_R")
		)
		(pad "A72" smd rect
			(at 31.500064 0 180)
			(size 0.762 4.2164)
			(layers "F.Cu" "F.Mask" "F.Paste")
			(net "UART_T7_NODE2_RXD_R")
		)
		(pad "A73" smd rect
			(at 32.500062 0 180)
			(size 0.762 4.2164)
			(layers "F.Cu" "F.Mask" "F.Paste")
			(net "UART_T7_NODE2_TXD_R")
		)
		(pad "A74" smd rect
			(at 33.50006 0 180)
			(size 0.762 4.2164)
			(layers "F.Cu" "F.Mask" "F.Paste")
			(net "GND")
		)
		(pad "A75" smd rect
			(at 34.500058 0 180)
			(size 0.762 4.2164)
			(layers "F.Cu" "F.Mask" "F.Paste")
			(net "UART_T7_NODE3_RXD_R")
		)
		(pad "A76" smd rect
			(at 35.500056 0 180)
			(size 0.762 4.2164)
			(layers "F.Cu" "F.Mask" "F.Paste")
			(net "UART_T7_NODE3_TXD_R")
		)
		(pad "A77" smd rect
			(at 36.500054 0 180)
			(size 0.762 4.2164)
			(layers "F.Cu" "F.Mask" "F.Paste")
			(net "UART_T7_NODE4_RXD_R")
		)
		(pad "A78" smd rect
			(at 37.500052 0 180)
			(size 0.762 4.2164)
			(layers "F.Cu" "F.Mask" "F.Paste")
			(net "UART_T7_NODE4_TXD_R")
		)
		(pad "A79" smd rect
			(at 38.50005 0 180)
			(size 0.762 4.2164)
			(layers "F.Cu" "F.Mask" "F.Paste")
			(net "GND")
		)
		(pad "A80" smd rect
			(at 39.500048 0 180)
			(size 0.762 4.2164)
			(layers "F.Cu" "F.Mask" "F.Paste")
			(net "PSU_ALERT_R_N")
		)
		(pad "A81" smd rect
			(at 40.500046 0 180)
			(size 0.762 4.2164)
			(layers "F.Cu" "F.Mask" "F.Paste")
			(net "T5_NODE1_EN_R")
		)
		(pad "A82" smd rect
			(at 41.500044 0 180)
			(size 0.762 4.2164)
			(layers "F.Cu" "F.Mask" "F.Paste")
			(net "T5_NODE2_EN_R")
		)
		(pad "B1" smd rect
			(at -41.500044 0 180)
			(size 0.762 4.2164)
			(layers "F.Cu" "F.Mask" "F.Paste")
			(net "GND")
		)
		(pad "B2" smd rect
			(at -40.500046 0 180)
			(size 0.762 4.2164)
			(layers "F.Cu" "F.Mask" "F.Paste")
			(net "LAN2_P1_P")
		)
		(pad "B3" smd rect
			(at -39.500048 0 180)
			(size 0.762 4.2164)
			(layers "F.Cu" "F.Mask" "F.Paste")
			(net "LAN2_P1_N")
		)
		(pad "B4" smd rect
			(at -38.50005 0 180)
			(size 0.762 4.2164)
			(layers "F.Cu" "F.Mask" "F.Paste")
			(net "GND")
		)
		(pad "B5" smd rect
			(at -37.500052 0 180)
			(size 0.762 4.2164)
			(layers "F.Cu" "F.Mask" "F.Paste")
			(net "LAN2_P2_P")
		)
		(pad "B6" smd rect
			(at -36.500054 0 180)
			(size 0.762 4.2164)
			(layers "F.Cu" "F.Mask" "F.Paste")
			(net "LAN2_P2_N")
		)
		(pad "B7" smd rect
			(at -35.500056 0 180)
			(size 0.762 4.2164)
			(layers "F.Cu" "F.Mask" "F.Paste")
			(net "GND")
		)
		(pad "B8" smd rect
			(at -34.500058 0 180)
			(size 0.762 4.2164)
			(layers "F.Cu" "F.Mask" "F.Paste")
			(net "GND")
		)
		(pad "B9" smd rect
			(at -33.50006 0 180)
			(size 0.762 4.2164)
			(layers "F.Cu" "F.Mask" "F.Paste")
			(net "GND")
		)
		(pad "B10" smd rect
			(at -32.500062 0 180)
			(size 0.762 4.2164)
			(layers "F.Cu" "F.Mask" "F.Paste")
			(net "I2C_PDB_R_SCL")
		)
		(pad "B11" smd rect
			(at -31.500064 0 180)
			(size 0.762 4.2164)
			(layers "F.Cu" "F.Mask" "F.Paste")
			(net "I2C_PDB_R_SDA")
		)
		(pad "B12" smd rect
			(at -28.50007 0 180)
			(size 0.762 4.2164)
			(layers "F.Cu" "F.Mask" "F.Paste")
			(net "P3V3_NODE1")
		)
		(pad "B13" smd rect
			(at -27.500072 0 180)
			(size 0.762 4.2164)
			(layers "F.Cu" "F.Mask" "F.Paste")
			(net "GND36")
		)
		(pad "B14" smd rect
			(at -26.500074 0 180)
			(size 0.762 4.2164)
			(layers "F.Cu" "F.Mask" "F.Paste")
			(net "Net_222")
		)
		(pad "B15" smd rect
			(at -25.500076 0 180)
			(size 0.762 4.2164)
			(layers "F.Cu" "F.Mask" "F.Paste")
			(net "Net_223")
		)
		(pad "B16" smd rect
			(at -24.500078 0 180)
			(size 0.762 4.2164)
			(layers "F.Cu" "F.Mask" "F.Paste")
			(net "GND37")
		)
		(pad "B17" smd rect
			(at -23.50008 -0.499872 180)
			(size 0.762 3.2004)
			(layers "F.Cu" "F.Mask" "F.Paste")
			(net "Net_224")
		)
		(pad "B18" smd rect
			(at -22.500082 0 180)
			(size 0.762 4.2164)
			(layers "F.Cu" "F.Mask" "F.Paste")
			(net "GND")
		)
		(pad "B19" smd rect
			(at -21.500084 0 180)
			(size 0.762 4.2164)
			(layers "F.Cu" "F.Mask" "F.Paste")
			(net "UART_RTS_RP5_L_N")
		)
		(pad "B20" smd rect
			(at -20.500086 0 180)
			(size 0.762 4.2164)
			(layers "F.Cu" "F.Mask" "F.Paste")
			(net "UART_DSR_RP5_L")
		)
		(pad "B21" smd rect
			(at -19.500088 0 180)
			(size 0.762 4.2164)
			(layers "F.Cu" "F.Mask" "F.Paste")
			(net "UART_RX_RP5_L")
		)
		(pad "B22" smd rect
			(at -18.50009 0 180)
			(size 0.762 4.2164)
			(layers "F.Cu" "F.Mask" "F.Paste")
			(net "UART_TX_RP5_L")
		)
		(pad "B23" smd rect
			(at -17.500092 0 180)
			(size 0.762 4.2164)
			(layers "F.Cu" "F.Mask" "F.Paste")
			(net "UART_DTR_RP5_L_N")
		)
		(pad "B24" smd rect
			(at -16.500094 0 180)
			(size 0.762 4.2164)
			(layers "F.Cu" "F.Mask" "F.Paste")
			(net "UART_CTS_RP5_L_N")
		)
		(pad "B25" smd rect
			(at -15.500096 0 180)
			(size 0.762 4.2164)
			(layers "F.Cu" "F.Mask" "F.Paste")
			(net "UART_RI_RP5_L_N_R")
		)
		(pad "B26" smd rect
			(at -14.500098 0 180)
			(size 0.762 4.2164)
			(layers "F.Cu" "F.Mask" "F.Paste")
			(net "GND")
		)
		(pad "B27" smd rect
			(at -13.5001 0 180)
			(size 0.762 4.2164)
			(layers "F.Cu" "F.Mask" "F.Paste")
			(net "FAN1_TACH_R")
		)
		(pad "B28" smd rect
			(at -12.500102 0 180)
			(size 0.762 4.2164)
			(layers "F.Cu" "F.Mask" "F.Paste")
			(net "FAN2_TACH_R")
		)
		(pad "B29" smd rect
			(at -11.500104 0 180)
			(size 0.762 4.2164)
			(layers "F.Cu" "F.Mask" "F.Paste")
			(net "FAN3_TACH_R")
		)
		(pad "B30" smd rect
			(at -10.500106 0 180)
			(size 0.762 4.2164)
			(layers "F.Cu" "F.Mask" "F.Paste")
			(net "GND")
		)
		(pad "B31" smd rect
			(at -9.500108 -0.499872 180)
			(size 0.762 3.2004)
			(layers "F.Cu" "F.Mask" "F.Paste")
			(net "T12_NODE1_EN_R")
		)
		(pad "B32" smd rect
			(at -8.50011 0 180)
			(size 0.762 4.2164)
			(layers "F.Cu" "F.Mask" "F.Paste")
			(net "T12_NODE2_EN_R")
		)
		(pad "B33" smd rect
			(at -7.500112 0 180)
			(size 0.762 4.2164)
			(layers "F.Cu" "F.Mask" "F.Paste")
			(net "T12_NODE3_EN_R")
		)
		(pad "B34" smd rect
			(at -6.500114 0 180)
			(size 0.762 4.2164)
			(layers "F.Cu" "F.Mask" "F.Paste")
			(net "T12_NODE4_EN_R")
		)
		(pad "B35" smd rect
			(at -5.500116 0 180)
			(size 0.762 4.2164)
			(layers "F.Cu" "F.Mask" "F.Paste")
			(net "GND")
		)
		(pad "B36" smd rect
			(at -4.500118 0 180)
			(size 0.762 4.2164)
			(layers "F.Cu" "F.Mask" "F.Paste")
			(net "UART_T12_NODE1_RXD_R")
		)
		(pad "B37" smd rect
			(at -3.50012 0 180)
			(size 0.762 4.2164)
			(layers "F.Cu" "F.Mask" "F.Paste")
			(net "UART_T12_NODE1_TXD_R")
		)
		(pad "B38" smd rect
			(at -2.500122 0 180)
			(size 0.762 4.2164)
			(layers "F.Cu" "F.Mask" "F.Paste")
			(net "UART_T12_NODE2_RXD_R")
		)
	)
)
